(kicad_pcb
	(version 20241229)
	(generator "pcbnew")
	(generator_version "9.0")
	(general
		(thickness 1.711)
		(legacy_teardrops no)
	)
	(paper "A4")
	(title_block
		(title "Antmicro Baseboard for Jetson AGX Thor")
		(date "2026-02-18")
		(rev "1.1.0")
		(company "Antmicro Ltd")
		(comment 1 "www.antmicro.com")
		(comment 9 "footprint 270 of 1170 (U30), pads 69-78 of 78")
	)
	(layers
		(0 "F.Cu" signal)
		(4 "In1.Cu" signal)
		(6 "In2.Cu" signal)
		(8 "In3.Cu" signal)
		(10 "In4.Cu" jumper)
		(12 "In5.Cu" signal)
		(14 "In6.Cu" signal)
		(16 "In7.Cu" signal)
		(18 "In8.Cu" signal)
		(2 "B.Cu" signal)
		(9 "F.Adhes" user "F.Adhesive")
		(11 "B.Adhes" user "B.Adhesive")
		(13 "F.Paste" user)
		(15 "B.Paste" user)
		(5 "F.SilkS" user "F.Silkscreen")
		(7 "B.SilkS" user "B.Silkscreen")
		(1 "F.Mask" user)
		(3 "B.Mask" user)
		(17 "Dwgs.User" user "User.Drawings")
		(19 "Cmts.User" user "User.Comments")
		(21 "Eco1.User" user "User.Eco1")
		(23 "Eco2.User" user "User.Eco2")
		(25 "Edge.Cuts" user)
		(27 "Margin" user)
		(31 "F.CrtYd" user "F.Courtyard")
		(29 "B.CrtYd" user "B.Courtyard")
		(35 "F.Fab" user)
		(33 "B.Fab" user)
	)
	(footprint "antmicro-footprints:IC_TPS65987DDHRSHR"
		(layer "F.Cu")
		(at 200.599 78.48 180)
		(property "Reference" "U30"
			(at -4.801 4.98 180)
			(layer "F.SilkS")
			(effects
				(font
					(size 0.7 0.7)
					(thickness 0.15)
				)
				(justify right top)
			)
		)
		(property "Value" "TPS65988DHRSHR"
			(at 0 4.9 0)
			(layer "F.Fab")
			(effects
				(font
					(size 0.7 0.7)
					(thickness 0.15)
				)
				(justify right top)
			)
		)
		(property "Datasheet" "https://www.ti.com/lit/ds/symlink/tps65988.pdf?ts=1662726631004&ref_url=https%253A%252F%252Fwww.ti.com%252Fproduct%252FTPS65988"
			(at 0 0 0)
			(layer "F.Fab")
			(hide yes)
			(effects
				(font
					(size 1.27 1.27)
					(thickness 0.15)
				)
			)
		)
		(property "Description" "USB, Type-C Controller PMIC 56-VQFN (7x7)"
			(at 0 0 0)
			(layer "F.Fab")
			(hide yes)
			(effects
				(font
					(size 1.27 1.27)
					(thickness 0.15)
				)
			)
		)
		(property "MPN" "TPS65988DHRSHR "
			(at 0 0 180)
			(unlocked yes)
			(layer "F.Fab")
			(hide yes)
			(effects
				(font
					(size 1 1)
					(thickness 0.15)
				)
			)
		)
		(property "Manufacturer" "Texas Instruments"
			(at 0 0 180)
			(unlocked yes)
			(layer "F.Fab")
			(hide yes)
			(effects
				(font
					(size 1 1)
					(thickness 0.15)
				)
			)
		)
		(property "License" "Apache-2.0"
			(at 0 0 180)
			(unlocked yes)
			(layer "F.Fab")
			(hide yes)
			(effects
				(font
					(size 1 1)
					(thickness 0.15)
				)
			)
		)
		(property "Author" "Antmicro"
			(at 0 0 180)
			(unlocked yes)
			(layer "F.Fab")
			(hide yes)
			(effects
				(font
					(size 1 1)
					(thickness 0.15)
				)
			)
		)
		(sheetname "/USB DP Alt mode/")
		(sheetfile "usb_dp.kicad_sch")
		(attr smd)
		(pad "59" thru_hole circle
			(at -0.15 0 180)
			(size 0.45 0.45)
			(drill 0.1)
			(layers "*.Cu")
			(remove_unused_layers no)
			(net 1 "GND")
			(pinfunction "GND_EP")
			(pintype "power_in")
		)
		(pad "59" thru_hole circle
			(at 1.048 -2.504 180)
			(size 0.45 0.45)
			(drill 0.1)
			(layers "*.Cu")
			(remove_unused_layers no)
			(net 1 "GND")
			(pinfunction "GND_EP")
			(pintype "power_in")
		)
		(pad "59" thru_hole circle
			(at 1.048 -1.327 180)
			(size 0.45 0.45)
			(drill 0.1)
			(layers "*.Cu")
			(remove_unused_layers no)
			(net 1 "GND")
			(pinfunction "GND_EP")
			(pintype "power_in")
		)
		(pad "59" thru_hole circle
			(at 1.048 1.322 180)
			(size 0.45 0.45)
			(drill 0.1)
			(layers "*.Cu")
			(remove_unused_layers no)
			(net 1 "GND")
			(pinfunction "GND_EP")
			(pintype "power_in")
		)
		(pad "59" thru_hole circle
			(at 1.048 2.496 180)
			(size 0.45 0.45)
			(drill 0.1)
			(layers "*.Cu")
			(remove_unused_layers no)
			(net 1 "GND")
			(pinfunction "GND_EP")
			(pintype "power_in")
		)
		(pad "59" thru_hole circle
			(at 1.05 0 180)
			(size 0.45 0.45)
			(drill 0.1)
			(layers "*.Cu")
			(remove_unused_layers no)
			(net 1 "GND")
			(pinfunction "GND_EP")
			(pintype "power_in")
		)
		(pad "59" smd roundrect
			(at 1.05 0 270)
			(size 5.5 3.4)
			(layers "F.Cu" "F.Mask")
			(roundrect_rratio 0.02941176471)
			(net 1 "GND")
			(pinfunction "GND_EP")
			(pintype "power_in")
			(solder_mask_margin 0.05)
		)
		(pad "59" thru_hole circle
			(at 2.248 -1.327 180)
			(size 0.45 0.45)
			(drill 0.1)
			(layers "*.Cu")
			(remove_unused_layers no)
			(net 1 "GND")
			(pinfunction "GND_EP")
			(pintype "power_in")
		)
		(pad "59" thru_hole circle
			(at 2.248 -0.001 180)
			(size 0.45 0.45)
			(drill 0.1)
			(layers "*.Cu")
			(remove_unused_layers no)
			(net 1 "GND")
			(pinfunction "GND_EP")
			(pintype "power_in")
		)
		(pad "59" thru_hole circle
			(at 2.248 1.322 180)
			(size 0.45 0.45)
			(drill 0.1)
			(layers "*.Cu")
			(remove_unused_layers no)
			(net 1 "GND")
			(pinfunction "GND_EP")
			(pintype "power_in")
		)
	)
)
